# S9S_MB_2U (Grand Teton) — schematic netlist excerpt (pin names and nets, part order shuffled) for the footprints in the layout excerpt that follows; sources: Cadence DE-HDL packaged netlist, KiCad conversion of 03242023_DA0F0TMBIJ0_F0T_Motherboard_J_brd_V01_OCP.brd

R2707  Q_RES  0 5% CHIP  pkg 0402LF  page 234 : A = SMB_BMC_SWB_EN ; B = SMB_BMC_SWB_EN_R
C237  Q_CAP  10UF 6.3V 20% X6S  pkg C0402  page 77 : A = PVCCIN_CPU1 ; B = GND

(kicad_pcb
	(version 20260206)
	(generator "pcbnew")
	(generator_version "10.0")
	(general
		(thickness 1.6)
		(legacy_teardrops no)
	)
	(paper "A4")
	(title_block
		(title "03242023_DA0F0TMBIJ0_F0T_Motherboard_J_brd_V01_OCP.brd")
		(comment 1 "Grand Teton / footprints 3447-3448 of 6105")
	)
	(layers
		(0 "F.Cu" signal "TOP")
		(4 "In1.Cu" signal "GND")
		(6 "In2.Cu" signal "IN1")
		(8 "In3.Cu" signal "GND1")
		(10 "In4.Cu" signal "IN2")
		(12 "In5.Cu" signal "GND2")
		(14 "In6.Cu" signal "IN3")
		(16 "In7.Cu" signal "GND3")
		(18 "In8.Cu" signal "VCC")
		(20 "In9.Cu" signal "VCC1")
		(22 "In10.Cu" signal "GND4")
		(24 "In11.Cu" signal "IN4")
		(26 "In12.Cu" signal "GND5")
		(28 "In13.Cu" signal "IN5")
		(30 "In14.Cu" signal "GND6")
		(32 "In15.Cu" signal "IN6")
		(34 "In16.Cu" signal "GND7")
		(2 "B.Cu" signal "BOTTOM")
		(9 "F.Adhes" user "F.Adhesive")
		(11 "B.Adhes" user "B.Adhesive")
		(13 "F.Paste" user "Package Geometry/Pastemask Top")
		(15 "B.Paste" user "Package Geometry/Pastemask Bottom")
		(5 "F.SilkS" user "Ref Des/Silkscreen Top")
		(7 "B.SilkS" user "Ref Des/Silkscreen Bottom")
		(1 "F.Mask" user "Board Geometry/Soldermask Top")
		(3 "B.Mask" user "Board Geometry/Soldermask Bottom")
		(17 "Dwgs.User" user "User.Drawings")
		(19 "Cmts.User" user "User.Comments")
		(21 "Eco1.User" user "User.Eco1")
		(23 "Eco2.User" user "User.Eco2")
		(25 "Edge.Cuts" user "Board Geometry/Outline")
		(27 "Margin" user)
		(31 "F.CrtYd" user "Package Geometry/Place Bound Top")
		(29 "B.CrtYd" user "Package Geometry/Place Bound Bottom")
		(35 "F.Fab" user "Ref Des/Assembly Top")
		(33 "B.Fab" user "Ref Des/Assembly Bottom")
	)
	(footprint ""
		(layer "F.Cu")
		(at 165.15715 -431.087276 -90)
		(property "Reference" "R2707"
			(at 0 0 270)
			(layer "F.SilkS")
			(hide yes)
			(effects
				(font
					(size 1.27 1.27)
				)
			)
		)
		(property "Value" ""
			(at 0 0 270)
			(layer "F.Fab")
			(effects
				(font
					(size 1.27 1.27)
				)
			)
		)
		(duplicate_pad_numbers_are_jumpers no)
		(fp_line
			(start -0.7874 0.4064)
			(end -0.7874 -0.4064)
			(stroke
				(width 0.1524)
				(type default)
			)
			(layer "F.SilkS")
		)
		(fp_line
			(start 0.7874 0.4064)
			(end -0.7874 0.4064)
			(stroke
				(width 0.1524)
				(type default)
			)
			(layer "F.SilkS")
		)
		(fp_line
			(start -0.7874 -0.4064)
			(end 0.7874 -0.4064)
			(stroke
				(width 0.1524)
				(type default)
			)
			(layer "F.SilkS")
		)
		(fp_line
			(start 0.7874 -0.4064)
			(end 0.7874 0.4064)
			(stroke
				(width 0.1524)
				(type default)
			)
			(layer "F.SilkS")
		)
		(fp_line
			(start -0.67945 0.3048)
			(end -0.67945 -0.305054)
			(stroke
				(width 0.1)
				(type default)
			)
			(layer "F.Fab")
		)
		(fp_line
			(start -0.12065 0.3048)
			(end -0.67945 0.3048)
			(stroke
				(width 0.1)
				(type default)
			)
			(layer "F.Fab")
		)
		(fp_line
			(start 0.120396 0.3048)
			(end 0.120396 0.2794)
			(stroke
				(width 0.1)
				(type default)
			)
			(layer "F.Fab")
		)
		(fp_line
			(start 0.67945 0.3048)
			(end 0.120396 0.3048)
			(stroke
				(width 0.1)
				(type default)
			)
			(layer "F.Fab")
		)
		(fp_line
			(start -0.12065 0.2794)
			(end -0.12065 0.3048)
			(stroke
				(width 0.1)
				(type default)
			)
			(layer "F.Fab")
		)
		(fp_line
			(start 0.120396 0.2794)
			(end -0.12065 0.2794)
			(stroke
				(width 0.1)
				(type default)
			)
			(layer "F.Fab")
		)
		(fp_line
			(start -0.12065 -0.2794)
			(end 0.12065 -0.2794)
			(stroke
				(width 0.1)
				(type default)
			)
			(layer "F.Fab")
		)
		(fp_line
			(start 0.12065 -0.2794)
			(end 0.12065 -0.3048)
			(stroke
				(width 0.1)
				(type default)
			)
			(layer "F.Fab")
		)
		(fp_line
			(start 0.12065 -0.3048)
			(end 0.67945 -0.3048)
			(stroke
				(width 0.1)
				(type default)
			)
			(layer "F.Fab")
		)
		(fp_line
			(start 0.67945 -0.3048)
			(end 0.67945 0.3048)
			(stroke
				(width 0.1)
				(type default)
			)
			(layer "F.Fab")
		)
		(fp_line
			(start -0.67945 -0.305054)
			(end -0.12065 -0.305054)
			(stroke
				(width 0.1)
				(type default)
			)
			(layer "F.Fab")
		)
		(fp_line
			(start -0.12065 -0.305054)
			(end -0.12065 -0.2794)
			(stroke
				(width 0.1)
				(type default)
			)
			(layer "F.Fab")
		)
		(pad "1" smd circle
			(at -0.40005 0 270)
			(size 0 0)
			(layers "F.Cu" "F.Mask" "F.Paste")
			(net "SMB_BMC_SWB_EN")
		)
		(pad "2" smd circle
			(at 0.40005 0 270)
			(size 0 0)
			(layers "F.Cu" "F.Mask" "F.Paste")
			(net "SMB_BMC_SWB_EN_R")
		)
	)
	(footprint ""
		(layer "F.Cu")
		(at 105.315004 -245.634256 -90)
		(property "Reference" "C237"
			(at 0 0 270)
			(layer "F.SilkS")
			(hide yes)
			(effects
				(font
					(size 1.27 1.27)
				)
			)
		)
		(property "Value" ""
			(at 0 0 270)
			(layer "F.Fab")
			(effects
				(font
					(size 1.27 1.27)
				)
			)
		)
		(duplicate_pad_numbers_are_jumpers no)
		(fp_line
			(start -0.7874 0.4064)
			(end -0.7874 -0.4064)
			(stroke
				(width 0.1524)
				(type default)
			)
			(layer "F.SilkS")
		)
		(fp_line
			(start 0.7874 0.4064)
			(end -0.7874 0.4064)
			(stroke
				(width 0.1524)
				(type default)
			)
			(layer "F.SilkS")
		)
		(fp_line
			(start -0.7874 -0.4064)
			(end 0.7874 -0.4064)
			(stroke
				(width 0.1524)
				(type default)
			)
			(layer "F.SilkS")
		)
		(fp_line
			(start 0.7874 -0.4064)
			(end 0.7874 0.4064)
			(stroke
				(width 0.1524)
				(type default)
			)
			(layer "F.SilkS")
		)
		(fp_line
			(start -0.67945 0.3048)
			(end -0.67945 -0.305054)
			(stroke
				(width 0.1)
				(type default)
			)
			(layer "F.Fab")
		)
		(fp_line
			(start -0.12065 0.3048)
			(end -0.67945 0.3048)
			(stroke
				(width 0.1)
				(type default)
			)
			(layer "F.Fab")
		)
		(fp_line
			(start 0.120396 0.3048)
			(end 0.120396 0.2794)
			(stroke
				(width 0.1)
				(type default)
			)
			(layer "F.Fab")
		)
		(fp_line
			(start 0.67945 0.3048)
			(end 0.120396 0.3048)
			(stroke
				(width 0.1)
				(type default)
			)
			(layer "F.Fab")
		)
		(fp_line
			(start -0.12065 0.2794)
			(end -0.12065 0.3048)
			(stroke
				(width 0.1)
				(type default)
			)
			(layer "F.Fab")
		)
		(fp_line
			(start 0.120396 0.2794)
			(end -0.12065 0.2794)
			(stroke
				(width 0.1)
				(type default)
			)
			(layer "F.Fab")
		)
		(fp_line
			(start -0.12065 -0.2794)
			(end 0.12065 -0.2794)
			(stroke
				(width 0.1)
				(type default)
			)
			(layer "F.Fab")
		)
		(fp_line
			(start 0.12065 -0.2794)
			(end 0.12065 -0.3048)
			(stroke
				(width 0.1)
				(type default)
			)
			(layer "F.Fab")
		)
		(fp_line
			(start 0.12065 -0.3048)
			(end 0.67945 -0.3048)
			(stroke
				(width 0.1)
				(type default)
			)
			(layer "F.Fab")
		)
		(fp_line
			(start 0.67945 -0.3048)
			(end 0.67945 0.3048)
			(stroke
				(width 0.1)
				(type default)
			)
			(layer "F.Fab")
		)
		(fp_line
			(start -0.67945 -0.305054)
			(end -0.12065 -0.305054)
			(stroke
				(width 0.1)
				(type default)
			)
			(layer "F.Fab")
		)
		(fp_line
			(start -0.12065 -0.305054)
			(end -0.12065 -0.2794)
			(stroke
				(width 0.1)
				(type default)
			)
			(layer "F.Fab")
		)
		(pad "1" smd circle
			(at -0.40005 0 270)
			(size 0 0)
			(layers "F.Cu" "F.Mask" "F.Paste")
			(net "PVCCIN_CPU1")
		)
		(pad "2" smd circle
			(at 0.40005 0 270)
			(size 0 0)
			(layers "F.Cu" "F.Mask" "F.Paste")
			(net "GND")
		)
	)
)
